# S9S_MB_2U (Grand Teton) — schematic netlist excerpt (pin names and nets, part order shuffled) for the footprints in the layout excerpt that follows; sources: Cadence DE-HDL packaged netlist, KiCad conversion of 03242023_DA0F0TMBIJ0_F0T_Motherboard_J_brd_V01_OCP.brd

PC2082  Q_CAP  10UF 16V 10% X6S  pkg C0805  page 156 : A = P12V_OCP_SFF ; B = GND
R3297  Q_RES  10K 1% CHIP  pkg 0402LF  page 190 : A = LED_HDD_ACTIVITY_B_N ; B = GND
R2287  Q_RES  10K 1% CHIP  pkg 0402LF  page 191 : A = P3V3_E1S_0 ; B = E1S_0_PERST1_CLKREQ_N

(kicad_pcb
	(version 20260206)
	(generator "pcbnew")
	(generator_version "10.0")
	(general
		(thickness 1.6)
		(legacy_teardrops no)
	)
	(paper "A4")
	(title_block
		(title "03242023_DA0F0TMBIJ0_F0T_Motherboard_J_brd_V01_OCP.brd")
		(comment 1 "Grand Teton / footprints 913-915 of 6105")
	)
	(layers
		(0 "F.Cu" signal "TOP")
		(4 "In1.Cu" signal "GND")
		(6 "In2.Cu" signal "IN1")
		(8 "In3.Cu" signal "GND1")
		(10 "In4.Cu" signal "IN2")
		(12 "In5.Cu" signal "GND2")
		(14 "In6.Cu" signal "IN3")
		(16 "In7.Cu" signal "GND3")
		(18 "In8.Cu" signal "VCC")
		(20 "In9.Cu" signal "VCC1")
		(22 "In10.Cu" signal "GND4")
		(24 "In11.Cu" signal "IN4")
		(26 "In12.Cu" signal "GND5")
		(28 "In13.Cu" signal "IN5")
		(30 "In14.Cu" signal "GND6")
		(32 "In15.Cu" signal "IN6")
		(34 "In16.Cu" signal "GND7")
		(2 "B.Cu" signal "BOTTOM")
		(9 "F.Adhes" user "F.Adhesive")
		(11 "B.Adhes" user "B.Adhesive")
		(13 "F.Paste" user "Package Geometry/Pastemask Top")
		(15 "B.Paste" user "Package Geometry/Pastemask Bottom")
		(5 "F.SilkS" user "Ref Des/Silkscreen Top")
		(7 "B.SilkS" user "Ref Des/Silkscreen Bottom")
		(1 "F.Mask" user "Board Geometry/Soldermask Top")
		(3 "B.Mask" user "Board Geometry/Soldermask Bottom")
		(17 "Dwgs.User" user "User.Drawings")
		(19 "Cmts.User" user "User.Comments")
		(21 "Eco1.User" user "User.Eco1")
		(23 "Eco2.User" user "User.Eco2")
		(25 "Edge.Cuts" user "Board Geometry/Outline")
		(27 "Margin" user)
		(31 "F.CrtYd" user "Package Geometry/Place Bound Top")
		(29 "B.CrtYd" user "Package Geometry/Place Bound Bottom")
		(35 "F.Fab" user "Ref Des/Assembly Top")
		(33 "B.Fab" user "Ref Des/Assembly Bottom")
	)
	(footprint ""
		(layer "F.Cu")
		(at 224.21215 -47.612046)
		(property "Reference" "R2287"
			(at 0 0 0)
			(layer "F.SilkS")
			(hide yes)
			(effects
				(font
					(size 1.27 1.27)
				)
			)
		)
		(property "Value" ""
			(at 0 0 0)
			(layer "F.Fab")
			(effects
				(font
					(size 1.27 1.27)
				)
			)
		)
		(duplicate_pad_numbers_are_jumpers no)
		(fp_line
			(start -0.7874 -0.4064)
			(end 0.7874 -0.4064)
			(stroke
				(width 0.1524)
				(type default)
			)
			(layer "F.SilkS")
		)
		(fp_line
			(start -0.7874 0.4064)
			(end -0.7874 -0.4064)
			(stroke
				(width 0.1524)
				(type default)
			)
			(layer "F.SilkS")
		)
		(fp_line
			(start 0.7874 -0.4064)
			(end 0.7874 0.4064)
			(stroke
				(width 0.1524)
				(type default)
			)
			(layer "F.SilkS")
		)
		(fp_line
			(start 0.7874 0.4064)
			(end -0.7874 0.4064)
			(stroke
				(width 0.1524)
				(type default)
			)
			(layer "F.SilkS")
		)
		(fp_line
			(start -0.67945 -0.305054)
			(end -0.12065 -0.305054)
			(stroke
				(width 0.1)
				(type default)
			)
			(layer "F.Fab")
		)
		(fp_line
			(start -0.67945 0.3048)
			(end -0.67945 -0.305054)
			(stroke
				(width 0.1)
				(type default)
			)
			(layer "F.Fab")
		)
		(fp_line
			(start -0.12065 -0.305054)
			(end -0.12065 -0.2794)
			(stroke
				(width 0.1)
				(type default)
			)
			(layer "F.Fab")
		)
		(fp_line
			(start -0.12065 -0.2794)
			(end 0.12065 -0.2794)
			(stroke
				(width 0.1)
				(type default)
			)
			(layer "F.Fab")
		)
		(fp_line
			(start -0.12065 0.2794)
			(end -0.12065 0.3048)
			(stroke
				(width 0.1)
				(type default)
			)
			(layer "F.Fab")
		)
		(fp_line
			(start -0.12065 0.3048)
			(end -0.67945 0.3048)
			(stroke
				(width 0.1)
				(type default)
			)
			(layer "F.Fab")
		)
		(fp_line
			(start 0.120396 0.2794)
			(end -0.12065 0.2794)
			(stroke
				(width 0.1)
				(type default)
			)
			(layer "F.Fab")
		)
		(fp_line
			(start 0.120396 0.3048)
			(end 0.120396 0.2794)
			(stroke
				(width 0.1)
				(type default)
			)
			(layer "F.Fab")
		)
		(fp_line
			(start 0.12065 -0.3048)
			(end 0.67945 -0.3048)
			(stroke
				(width 0.1)
				(type default)
			)
			(layer "F.Fab")
		)
		(fp_line
			(start 0.12065 -0.2794)
			(end 0.12065 -0.3048)
			(stroke
				(width 0.1)
				(type default)
			)
			(layer "F.Fab")
		)
		(fp_line
			(start 0.67945 -0.3048)
			(end 0.67945 0.3048)
			(stroke
				(width 0.1)
				(type default)
			)
			(layer "F.Fab")
		)
		(fp_line
			(start 0.67945 0.3048)
			(end 0.120396 0.3048)
			(stroke
				(width 0.1)
				(type default)
			)
			(layer "F.Fab")
		)
		(pad "1" smd circle
			(at -0.40005 0)
			(size 0 0)
			(layers "F.Cu" "F.Mask" "F.Paste")
			(net "P3V3_E1S_0")
		)
		(pad "2" smd circle
			(at 0.40005 0)
			(size 0 0)
			(layers "F.Cu" "F.Mask" "F.Paste")
			(net "E1S_0_PERST1_CLKREQ_N")
		)
	)
	(footprint ""
		(layer "F.Cu")
		(at 440.0804 -20.440396 180)
		(property "Reference" "PC2082"
			(at 0 0 180)
			(layer "F.SilkS")
			(hide yes)
			(effects
				(font
					(size 1.27 1.27)
				)
			)
		)
		(property "Value" ""
			(at 0 0 180)
			(layer "F.Fab")
			(effects
				(font
					(size 1.27 1.27)
				)
			)
		)
		(duplicate_pad_numbers_are_jumpers no)
		(fp_line
			(start 1.524 0.762)
			(end -1.524 0.762)
			(stroke
				(width 0.1524)
				(type default)
			)
			(layer "F.SilkS")
		)
		(fp_line
			(start 1.524 -0.762)
			(end 1.524 0.762)
			(stroke
				(width 0.1524)
				(type default)
			)
			(layer "F.SilkS")
		)
		(fp_line
			(start -1.524 0.762)
			(end -1.524 -0.762)
			(stroke
				(width 0.1524)
				(type default)
			)
			(layer "F.SilkS")
		)
		(fp_line
			(start -1.524 -0.762)
			(end 1.524 -0.762)
			(stroke
				(width 0.1524)
				(type default)
			)
			(layer "F.SilkS")
		)
		(fp_line
			(start 1.1049 0.724916)
			(end 1.1049 -0.724916)
			(stroke
				(width 0.1)
				(type default)
			)
			(layer "F.Fab")
		)
		(fp_line
			(start 1.1049 -0.724916)
			(end -1.1049 -0.724916)
			(stroke
				(width 0.1)
				(type default)
			)
			(layer "F.Fab")
		)
		(fp_line
			(start -1.1049 0.724916)
			(end 1.1049 0.724916)
			(stroke
				(width 0.1)
				(type default)
			)
			(layer "F.Fab")
		)
		(fp_line
			(start -1.1049 -0.724916)
			(end -1.1049 0.724916)
			(stroke
				(width 0.1)
				(type default)
			)
			(layer "F.Fab")
		)
		(pad "1" smd rect
			(at -0.889 0)
			(size 1.016 1.27)
			(layers "F.Cu" "F.Mask" "F.Paste")
			(net "P12V_OCP_SFF")
		)
		(pad "2" smd rect
			(at 0.889 0)
			(size 1.016 1.27)
			(layers "F.Cu" "F.Mask" "F.Paste")
			(net "GND")
		)
	)
	(footprint ""
		(layer "F.Cu")
		(at 153.21788 -41.811448)
		(property "Reference" "R3297"
			(at 0 0 0)
			(layer "F.SilkS")
			(hide yes)
			(effects
				(font
					(size 1.27 1.27)
				)
			)
		)
		(property "Value" ""
			(at 0 0 0)
			(layer "F.Fab")
			(effects
				(font
					(size 1.27 1.27)
				)
			)
		)
		(duplicate_pad_numbers_are_jumpers no)
		(fp_line
			(start -0.7874 -0.4064)
			(end 0.7874 -0.4064)
			(stroke
				(width 0.1524)
				(type default)
			)
			(layer "F.SilkS")
		)
		(fp_line
			(start -0.7874 0.4064)
			(end -0.7874 -0.4064)
			(stroke
				(width 0.1524)
				(type default)
			)
			(layer "F.SilkS")
		)
		(fp_line
			(start 0.7874 -0.4064)
			(end 0.7874 0.4064)
			(stroke
				(width 0.1524)
				(type default)
			)
			(layer "F.SilkS")
		)
		(fp_line
			(start 0.7874 0.4064)
			(end -0.7874 0.4064)
			(stroke
				(width 0.1524)
				(type default)
			)
			(layer "F.SilkS")
		)
		(fp_line
			(start -0.67945 -0.305054)
			(end -0.12065 -0.305054)
			(stroke
				(width 0.1)
				(type default)
			)
			(layer "F.Fab")
		)
		(fp_line
			(start -0.67945 0.3048)
			(end -0.67945 -0.305054)
			(stroke
				(width 0.1)
				(type default)
			)
			(layer "F.Fab")
		)
		(fp_line
			(start -0.12065 -0.305054)
			(end -0.12065 -0.2794)
			(stroke
				(width 0.1)
				(type default)
			)
			(layer "F.Fab")
		)
		(fp_line
			(start -0.12065 -0.2794)
			(end 0.12065 -0.2794)
			(stroke
				(width 0.1)
				(type default)
			)
			(layer "F.Fab")
		)
		(fp_line
			(start -0.12065 0.2794)
			(end -0.12065 0.3048)
			(stroke
				(width 0.1)
				(type default)
			)
			(layer "F.Fab")
		)
		(fp_line
			(start -0.12065 0.3048)
			(end -0.67945 0.3048)
			(stroke
				(width 0.1)
				(type default)
			)
			(layer "F.Fab")
		)
		(fp_line
			(start 0.120396 0.2794)
			(end -0.12065 0.2794)
			(stroke
				(width 0.1)
				(type default)
			)
			(layer "F.Fab")
		)
		(fp_line
			(start 0.120396 0.3048)
			(end 0.120396 0.2794)
			(stroke
				(width 0.1)
				(type default)
			)
			(layer "F.Fab")
		)
		(fp_line
			(start 0.12065 -0.3048)
			(end 0.67945 -0.3048)
			(stroke
				(width 0.1)
				(type default)
			)
			(layer "F.Fab")
		)
		(fp_line
			(start 0.12065 -0.2794)
			(end 0.12065 -0.3048)
			(stroke
				(width 0.1)
				(type default)
			)
			(layer "F.Fab")
		)
		(fp_line
			(start 0.67945 -0.3048)
			(end 0.67945 0.3048)
			(stroke
				(width 0.1)
				(type default)
			)
			(layer "F.Fab")
		)
		(fp_line
			(start 0.67945 0.3048)
			(end 0.120396 0.3048)
			(stroke
				(width 0.1)
				(type default)
			)
			(layer "F.Fab")
		)
		(pad "1" smd circle
			(at -0.40005 0)
			(size 0 0)
			(layers "F.Cu" "F.Mask" "F.Paste")
			(net "LED_HDD_ACTIVITY_B_N")
		)
		(pad "2" smd circle
			(at 0.40005 0)
			(size 0 0)
			(layers "F.Cu" "F.Mask" "F.Paste")
			(net "GND")
		)
	)
)
